(kicad_pcb
	(version 20260206)
	(generator "pcbnew")
	(generator_version "10.0")
	(general
		(thickness 1.6)
		(legacy_teardrops no)
	)
	(paper "A4")
	(title_block
		(title "03242023_DA0F0TMBIJ0_F0T_Motherboard_J_brd_V01_OCP.brd")
		(comment 1 "Grand Teton / footprints 3734-3739 of 6105")
	)
	(layers
		(0 "F.Cu" signal "TOP")
		(4 "In1.Cu" signal "GND")
		(6 "In2.Cu" signal "IN1")
		(8 "In3.Cu" signal "GND1")
		(10 "In4.Cu" signal "IN2")
		(12 "In5.Cu" signal "GND2")
		(14 "In6.Cu" signal "IN3")
		(16 "In7.Cu" signal "GND3")
		(18 "In8.Cu" signal "VCC")
		(20 "In9.Cu" signal "VCC1")
		(22 "In10.Cu" signal "GND4")
		(24 "In11.Cu" signal "IN4")
		(26 "In12.Cu" signal "GND5")
		(28 "In13.Cu" signal "IN5")
		(30 "In14.Cu" signal "GND6")
		(32 "In15.Cu" signal "IN6")
		(34 "In16.Cu" signal "GND7")
		(2 "B.Cu" signal "BOTTOM")
		(9 "F.Adhes" user "F.Adhesive")
		(11 "B.Adhes" user "B.Adhesive")
		(13 "F.Paste" user "Package Geometry/Pastemask Top")
		(15 "B.Paste" user "Package Geometry/Pastemask Bottom")
		(5 "F.SilkS" user "Ref Des/Silkscreen Top")
		(7 "B.SilkS" user "Ref Des/Silkscreen Bottom")
		(1 "F.Mask" user "Board Geometry/Soldermask Top")
		(3 "B.Mask" user "Board Geometry/Soldermask Bottom")
		(17 "Dwgs.User" user "User.Drawings")
		(19 "Cmts.User" user "User.Comments")
		(21 "Eco1.User" user "User.Eco1")
		(23 "Eco2.User" user "User.Eco2")
		(25 "Edge.Cuts" user "Board Geometry/Outline")
		(27 "Margin" user)
		(31 "F.CrtYd" user "Package Geometry/Place Bound Top")
		(29 "B.CrtYd" user "Package Geometry/Place Bound Bottom")
		(35 "F.Fab" user "Ref Des/Assembly Top")
		(33 "B.Fab" user "Ref Des/Assembly Bottom")
	)
	(footprint ""
		(layer "F.Cu")
		(at 82.322924 -152.621742 90)
		(property "Reference" "C537"
			(at 0 0 90)
			(layer "F.SilkS")
			(hide yes)
			(effects
				(font
					(size 1.27 1.27)
				)
			)
		)
		(property "Value" ""
			(at 0 0 90)
			(layer "F.Fab")
			(effects
				(font
					(size 1.27 1.27)
				)
			)
		)
		(duplicate_pad_numbers_are_jumpers no)
		(fp_line
			(start 0.7874 -0.4064)
			(end 0.7874 0.4064)
			(stroke
				(width 0.1524)
				(type default)
			)
			(layer "F.SilkS")
		)
		(fp_line
			(start -0.7874 -0.4064)
			(end 0.7874 -0.4064)
			(stroke
				(width 0.1524)
				(type default)
			)
			(layer "F.SilkS")
		)
		(fp_line
			(start 0.7874 0.4064)
			(end -0.7874 0.4064)
			(stroke
				(width 0.1524)
				(type default)
			)
			(layer "F.SilkS")
		)
		(fp_line
			(start -0.7874 0.4064)
			(end -0.7874 -0.4064)
			(stroke
				(width 0.1524)
				(type default)
			)
			(layer "F.SilkS")
		)
		(fp_line
			(start -0.12065 -0.305054)
			(end -0.12065 -0.2794)
			(stroke
				(width 0.1)
				(type default)
			)
			(layer "F.Fab")
		)
		(fp_line
			(start -0.67945 -0.305054)
			(end -0.12065 -0.305054)
			(stroke
				(width 0.1)
				(type default)
			)
			(layer "F.Fab")
		)
		(fp_line
			(start 0.67945 -0.3048)
			(end 0.67945 0.3048)
			(stroke
				(width 0.1)
				(type default)
			)
			(layer "F.Fab")
		)
		(fp_line
			(start 0.12065 -0.3048)
			(end 0.67945 -0.3048)
			(stroke
				(width 0.1)
				(type default)
			)
			(layer "F.Fab")
		)
		(fp_line
			(start 0.12065 -0.2794)
			(end 0.12065 -0.3048)
			(stroke
				(width 0.1)
				(type default)
			)
			(layer "F.Fab")
		)
		(fp_line
			(start -0.12065 -0.2794)
			(end 0.12065 -0.2794)
			(stroke
				(width 0.1)
				(type default)
			)
			(layer "F.Fab")
		)
		(fp_line
			(start 0.120396 0.2794)
			(end -0.12065 0.2794)
			(stroke
				(width 0.1)
				(type default)
			)
			(layer "F.Fab")
		)
		(fp_line
			(start -0.12065 0.2794)
			(end -0.12065 0.3048)
			(stroke
				(width 0.1)
				(type default)
			)
			(layer "F.Fab")
		)
		(fp_line
			(start 0.67945 0.3048)
			(end 0.120396 0.3048)
			(stroke
				(width 0.1)
				(type default)
			)
			(layer "F.Fab")
		)
		(fp_line
			(start 0.120396 0.3048)
			(end 0.120396 0.2794)
			(stroke
				(width 0.1)
				(type default)
			)
			(layer "F.Fab")
		)
		(fp_line
			(start -0.12065 0.3048)
			(end -0.67945 0.3048)
			(stroke
				(width 0.1)
				(type default)
			)
			(layer "F.Fab")
		)
		(fp_line
			(start -0.67945 0.3048)
			(end -0.67945 -0.305054)
			(stroke
				(width 0.1)
				(type default)
			)
			(layer "F.Fab")
		)
		(pad "1" smd circle
			(at -0.40005 0 90)
			(size 0 0)
			(layers "F.Cu" "F.Mask" "F.Paste")
			(net "P3V3_AUX")
		)
		(pad "2" smd circle
			(at 0.40005 0 90)
			(size 0 0)
			(layers "F.Cu" "F.Mask" "F.Paste")
			(net "GND")
		)
	)
	(footprint ""
		(layer "F.Cu")
		(at 406.124664 -363.008926 180)
		(property "Reference" "R335"
			(at 0 0 180)
			(layer "F.SilkS")
			(hide yes)
			(effects
				(font
					(size 1.27 1.27)
				)
			)
		)
		(property "Value" ""
			(at 0 0 180)
			(layer "F.Fab")
			(effects
				(font
					(size 1.27 1.27)
				)
			)
		)
		(duplicate_pad_numbers_are_jumpers no)
		(fp_line
			(start 0.7874 0.4064)
			(end -0.7874 0.4064)
			(stroke
				(width 0.1524)
				(type default)
			)
			(layer "F.SilkS")
		)
		(fp_line
			(start 0.7874 -0.4064)
			(end 0.7874 0.4064)
			(stroke
				(width 0.1524)
				(type default)
			)
			(layer "F.SilkS")
		)
		(fp_line
			(start -0.7874 0.4064)
			(end -0.7874 -0.4064)
			(stroke
				(width 0.1524)
				(type default)
			)
			(layer "F.SilkS")
		)
		(fp_line
			(start -0.7874 -0.4064)
			(end 0.7874 -0.4064)
			(stroke
				(width 0.1524)
				(type default)
			)
			(layer "F.SilkS")
		)
		(fp_line
			(start 0.67945 0.3048)
			(end 0.120396 0.3048)
			(stroke
				(width 0.1)
				(type default)
			)
			(layer "F.Fab")
		)
		(fp_line
			(start 0.67945 -0.3048)
			(end 0.67945 0.3048)
			(stroke
				(width 0.1)
				(type default)
			)
			(layer "F.Fab")
		)
		(fp_line
			(start 0.12065 -0.2794)
			(end 0.12065 -0.3048)
			(stroke
				(width 0.1)
				(type default)
			)
			(layer "F.Fab")
		)
		(fp_line
			(start 0.12065 -0.3048)
			(end 0.67945 -0.3048)
			(stroke
				(width 0.1)
				(type default)
			)
			(layer "F.Fab")
		)
		(fp_line
			(start 0.120396 0.3048)
			(end 0.120396 0.2794)
			(stroke
				(width 0.1)
				(type default)
			)
			(layer "F.Fab")
		)
		(fp_line
			(start 0.120396 0.2794)
			(end -0.12065 0.2794)
			(stroke
				(width 0.1)
				(type default)
			)
			(layer "F.Fab")
		)
		(fp_line
			(start -0.12065 0.3048)
			(end -0.67945 0.3048)
			(stroke
				(width 0.1)
				(type default)
			)
			(layer "F.Fab")
		)
		(fp_line
			(start -0.12065 0.2794)
			(end -0.12065 0.3048)
			(stroke
				(width 0.1)
				(type default)
			)
			(layer "F.Fab")
		)
		(fp_line
			(start -0.12065 -0.2794)
			(end 0.12065 -0.2794)
			(stroke
				(width 0.1)
				(type default)
			)
			(layer "F.Fab")
		)
		(fp_line
			(start -0.12065 -0.305054)
			(end -0.12065 -0.2794)
			(stroke
				(width 0.1)
				(type default)
			)
			(layer "F.Fab")
		)
		(fp_line
			(start -0.67945 0.3048)
			(end -0.67945 -0.305054)
			(stroke
				(width 0.1)
				(type default)
			)
			(layer "F.Fab")
		)
		(fp_line
			(start -0.67945 -0.305054)
			(end -0.12065 -0.305054)
			(stroke
				(width 0.1)
				(type default)
			)
			(layer "F.Fab")
		)
		(pad "1" smd circle
			(at -0.40005 0 180)
			(size 0 0)
			(layers "F.Cu" "F.Mask" "F.Paste")
			(net "P3V3_AUX")
		)
		(pad "2" smd circle
			(at 0.40005 0 180)
			(size 0 0)
			(layers "F.Cu" "F.Mask" "F.Paste")
			(net "PD_PIROM_CPU0_ADDR0")
		)
	)
	(footprint ""
		(layer "F.Cu")
		(at 118.542816 -251.375672 90)
		(property "Reference" "C263"
			(at 0 0 90)
			(layer "F.SilkS")
			(hide yes)
			(effects
				(font
					(size 1.27 1.27)
				)
			)
		)
		(property "Value" ""
			(at 0 0 90)
			(layer "F.Fab")
			(effects
				(font
					(size 1.27 1.27)
				)
			)
		)
		(duplicate_pad_numbers_are_jumpers no)
		(fp_line
			(start 0.7874 -0.4064)
			(end 0.7874 0.4064)
			(stroke
				(width 0.1524)
				(type default)
			)
			(layer "F.SilkS")
		)
		(fp_line
			(start -0.7874 -0.4064)
			(end 0.7874 -0.4064)
			(stroke
				(width 0.1524)
				(type default)
			)
			(layer "F.SilkS")
		)
		(fp_line
			(start 0.7874 0.4064)
			(end -0.7874 0.4064)
			(stroke
				(width 0.1524)
				(type default)
			)
			(layer "F.SilkS")
		)
		(fp_line
			(start -0.7874 0.4064)
			(end -0.7874 -0.4064)
			(stroke
				(width 0.1524)
				(type default)
			)
			(layer "F.SilkS")
		)
		(fp_line
			(start -0.12065 -0.305054)
			(end -0.12065 -0.2794)
			(stroke
				(width 0.1)
				(type default)
			)
			(layer "F.Fab")
		)
		(fp_line
			(start -0.67945 -0.305054)
			(end -0.12065 -0.305054)
			(stroke
				(width 0.1)
				(type default)
			)
			(layer "F.Fab")
		)
		(fp_line
			(start 0.67945 -0.3048)
			(end 0.67945 0.3048)
			(stroke
				(width 0.1)
				(type default)
			)
			(layer "F.Fab")
		)
		(fp_line
			(start 0.12065 -0.3048)
			(end 0.67945 -0.3048)
			(stroke
				(width 0.1)
				(type default)
			)
			(layer "F.Fab")
		)
		(fp_line
			(start 0.12065 -0.2794)
			(end 0.12065 -0.3048)
			(stroke
				(width 0.1)
				(type default)
			)
			(layer "F.Fab")
		)
		(fp_line
			(start -0.12065 -0.2794)
			(end 0.12065 -0.2794)
			(stroke
				(width 0.1)
				(type default)
			)
			(layer "F.Fab")
		)
		(fp_line
			(start 0.120396 0.2794)
			(end -0.12065 0.2794)
			(stroke
				(width 0.1)
				(type default)
			)
			(layer "F.Fab")
		)
		(fp_line
			(start -0.12065 0.2794)
			(end -0.12065 0.3048)
			(stroke
				(width 0.1)
				(type default)
			)
			(layer "F.Fab")
		)
		(fp_line
			(start 0.67945 0.3048)
			(end 0.120396 0.3048)
			(stroke
				(width 0.1)
				(type default)
			)
			(layer "F.Fab")
		)
		(fp_line
			(start 0.120396 0.3048)
			(end 0.120396 0.2794)
			(stroke
				(width 0.1)
				(type default)
			)
			(layer "F.Fab")
		)
		(fp_line
			(start -0.12065 0.3048)
			(end -0.67945 0.3048)
			(stroke
				(width 0.1)
				(type default)
			)
			(layer "F.Fab")
		)
		(fp_line
			(start -0.67945 0.3048)
			(end -0.67945 -0.305054)
			(stroke
				(width 0.1)
				(type default)
			)
			(layer "F.Fab")
		)
		(pad "1" smd circle
			(at -0.40005 0 90)
			(size 0 0)
			(layers "F.Cu" "F.Mask" "F.Paste")
			(net "PVCCIN_CPU1")
		)
		(pad "2" smd circle
			(at 0.40005 0 90)
			(size 0 0)
			(layers "F.Cu" "F.Mask" "F.Paste")
			(net "GND")
		)
	)
	(footprint ""
		(layer "F.Cu")
		(at 201.02068 -102.235)
		(property "Reference" "R4712"
			(at 0 0 0)
			(layer "F.SilkS")
			(hide yes)
			(effects
				(font
					(size 1.27 1.27)
				)
			)
		)
		(property "Value" ""
			(at 0 0 0)
			(layer "F.Fab")
			(effects
				(font
					(size 1.27 1.27)
				)
			)
		)
		(duplicate_pad_numbers_are_jumpers no)
		(fp_line
			(start -0.7874 -0.4064)
			(end 0.7874 -0.4064)
			(stroke
				(width 0.1524)
				(type default)
			)
			(layer "F.SilkS")
		)
		(fp_line
			(start -0.7874 0.4064)
			(end -0.7874 -0.4064)
			(stroke
				(width 0.1524)
				(type default)
			)
			(layer "F.SilkS")
		)
		(fp_line
			(start 0.7874 -0.4064)
			(end 0.7874 0.4064)
			(stroke
				(width 0.1524)
				(type default)
			)
			(layer "F.SilkS")
		)
		(fp_line
			(start 0.7874 0.4064)
			(end -0.7874 0.4064)
			(stroke
				(width 0.1524)
				(type default)
			)
			(layer "F.SilkS")
		)
		(fp_line
			(start -0.67945 -0.305054)
			(end -0.12065 -0.305054)
			(stroke
				(width 0.1)
				(type default)
			)
			(layer "F.Fab")
		)
		(fp_line
			(start -0.67945 0.3048)
			(end -0.67945 -0.305054)
			(stroke
				(width 0.1)
				(type default)
			)
			(layer "F.Fab")
		)
		(fp_line
			(start -0.12065 -0.305054)
			(end -0.12065 -0.2794)
			(stroke
				(width 0.1)
				(type default)
			)
			(layer "F.Fab")
		)
		(fp_line
			(start -0.12065 -0.2794)
			(end 0.12065 -0.2794)
			(stroke
				(width 0.1)
				(type default)
			)
			(layer "F.Fab")
		)
		(fp_line
			(start -0.12065 0.2794)
			(end -0.12065 0.3048)
			(stroke
				(width 0.1)
				(type default)
			)
			(layer "F.Fab")
		)
		(fp_line
			(start -0.12065 0.3048)
			(end -0.67945 0.3048)
			(stroke
				(width 0.1)
				(type default)
			)
			(layer "F.Fab")
		)
		(fp_line
			(start 0.120396 0.2794)
			(end -0.12065 0.2794)
			(stroke
				(width 0.1)
				(type default)
			)
			(layer "F.Fab")
		)
		(fp_line
			(start 0.120396 0.3048)
			(end 0.120396 0.2794)
			(stroke
				(width 0.1)
				(type default)
			)
			(layer "F.Fab")
		)
		(fp_line
			(start 0.12065 -0.3048)
			(end 0.67945 -0.3048)
			(stroke
				(width 0.1)
				(type default)
			)
			(layer "F.Fab")
		)
		(fp_line
			(start 0.12065 -0.2794)
			(end 0.12065 -0.3048)
			(stroke
				(width 0.1)
				(type default)
			)
			(layer "F.Fab")
		)
		(fp_line
			(start 0.67945 -0.3048)
			(end 0.67945 0.3048)
			(stroke
				(width 0.1)
				(type default)
			)
			(layer "F.Fab")
		)
		(fp_line
			(start 0.67945 0.3048)
			(end 0.120396 0.3048)
			(stroke
				(width 0.1)
				(type default)
			)
			(layer "F.Fab")
		)
		(pad "1" smd circle
			(at -0.40005 0)
			(size 0 0)
			(layers "F.Cu" "F.Mask" "F.Paste")
			(net "RST_PFR_OVR_RTC")
		)
		(pad "2" smd circle
			(at 0.40005 0)
			(size 0 0)
			(layers "F.Cu" "F.Mask" "F.Paste")
			(net "GND")
		)
	)
	(footprint ""
		(layer "F.Cu")
		(at 197.19036 -118.074948)
		(property "Reference" "R1469"
			(at 0 0 0)
			(layer "F.SilkS")
			(hide yes)
			(effects
				(font
					(size 1.27 1.27)
				)
			)
		)
		(property "Value" ""
			(at 0 0 0)
			(layer "F.Fab")
			(effects
				(font
					(size 1.27 1.27)
				)
			)
		)
		(duplicate_pad_numbers_are_jumpers no)
		(fp_line
			(start -0.7874 -0.4064)
			(end 0.7874 -0.4064)
			(stroke
				(width 0.1524)
				(type default)
			)
			(layer "F.SilkS")
		)
		(fp_line
			(start -0.7874 0.4064)
			(end -0.7874 -0.4064)
			(stroke
				(width 0.1524)
				(type default)
			)
			(layer "F.SilkS")
		)
		(fp_line
			(start 0.7874 -0.4064)
			(end 0.7874 0.4064)
			(stroke
				(width 0.1524)
				(type default)
			)
			(layer "F.SilkS")
		)
		(fp_line
			(start 0.7874 0.4064)
			(end -0.7874 0.4064)
			(stroke
				(width 0.1524)
				(type default)
			)
			(layer "F.SilkS")
		)
		(fp_line
			(start -0.67945 -0.305054)
			(end -0.12065 -0.305054)
			(stroke
				(width 0.1)
				(type default)
			)
			(layer "F.Fab")
		)
		(fp_line
			(start -0.67945 0.3048)
			(end -0.67945 -0.305054)
			(stroke
				(width 0.1)
				(type default)
			)
			(layer "F.Fab")
		)
		(fp_line
			(start -0.12065 -0.305054)
			(end -0.12065 -0.2794)
			(stroke
				(width 0.1)
				(type default)
			)
			(layer "F.Fab")
		)
		(fp_line
			(start -0.12065 -0.2794)
			(end 0.12065 -0.2794)
			(stroke
				(width 0.1)
				(type default)
			)
			(layer "F.Fab")
		)
		(fp_line
			(start -0.12065 0.2794)
			(end -0.12065 0.3048)
			(stroke
				(width 0.1)
				(type default)
			)
			(layer "F.Fab")
		)
		(fp_line
			(start -0.12065 0.3048)
			(end -0.67945 0.3048)
			(stroke
				(width 0.1)
				(type default)
			)
			(layer "F.Fab")
		)
		(fp_line
			(start 0.120396 0.2794)
			(end -0.12065 0.2794)
			(stroke
				(width 0.1)
				(type default)
			)
			(layer "F.Fab")
		)
		(fp_line
			(start 0.120396 0.3048)
			(end 0.120396 0.2794)
			(stroke
				(width 0.1)
				(type default)
			)
			(layer "F.Fab")
		)
		(fp_line
			(start 0.12065 -0.3048)
			(end 0.67945 -0.3048)
			(stroke
				(width 0.1)
				(type default)
			)
			(layer "F.Fab")
		)
		(fp_line
			(start 0.12065 -0.2794)
			(end 0.12065 -0.3048)
			(stroke
				(width 0.1)
				(type default)
			)
			(layer "F.Fab")
		)
		(fp_line
			(start 0.67945 -0.3048)
			(end 0.67945 0.3048)
			(stroke
				(width 0.1)
				(type default)
			)
			(layer "F.Fab")
		)
		(fp_line
			(start 0.67945 0.3048)
			(end 0.120396 0.3048)
			(stroke
				(width 0.1)
				(type default)
			)
			(layer "F.Fab")
		)
		(pad "1" smd circle
			(at -0.40005 0)
			(size 0 0)
			(layers "F.Cu" "F.Mask" "F.Paste")
			(net "RST_PLTRST_PLD_B_N")
		)
		(pad "2" smd circle
			(at 0.40005 0)
			(size 0 0)
			(layers "F.Cu" "F.Mask" "F.Paste")
			(net "RST_PLTRST_B_N")
		)
	)
	(footprint ""
		(layer "F.Cu")
		(at 263.805924 -75.61834 90)
		(property "Reference" "PR1327"
			(at 0 0 90)
			(layer "F.SilkS")
			(hide yes)
			(effects
				(font
					(size 1.27 1.27)
				)
			)
		)
		(property "Value" ""
			(at 0 0 90)
			(layer "F.Fab")
			(effects
				(font
					(size 1.27 1.27)
				)
			)
		)
		(duplicate_pad_numbers_are_jumpers no)
		(fp_line
			(start 0.7874 -0.4064)
			(end 0.7874 0.4064)
			(stroke
				(width 0.1524)
				(type default)
			)
			(layer "F.SilkS")
		)
		(fp_line
			(start -0.7874 -0.4064)
			(end 0.7874 -0.4064)
			(stroke
				(width 0.1524)
				(type default)
			)
			(layer "F.SilkS")
		)
		(fp_line
			(start 0.7874 0.4064)
			(end -0.7874 0.4064)
			(stroke
				(width 0.1524)
				(type default)
			)
			(layer "F.SilkS")
		)
		(fp_line
			(start -0.7874 0.4064)
			(end -0.7874 -0.4064)
			(stroke
				(width 0.1524)
				(type default)
			)
			(layer "F.SilkS")
		)
		(fp_line
			(start -0.12065 -0.305054)
			(end -0.12065 -0.2794)
			(stroke
				(width 0.1)
				(type default)
			)
			(layer "F.Fab")
		)
		(fp_line
			(start -0.67945 -0.305054)
			(end -0.12065 -0.305054)
			(stroke
				(width 0.1)
				(type default)
			)
			(layer "F.Fab")
		)
		(fp_line
			(start 0.67945 -0.3048)
			(end 0.67945 0.3048)
			(stroke
				(width 0.1)
				(type default)
			)
			(layer "F.Fab")
		)
		(fp_line
			(start 0.12065 -0.3048)
			(end 0.67945 -0.3048)
			(stroke
				(width 0.1)
				(type default)
			)
			(layer "F.Fab")
		)
		(fp_line
			(start 0.12065 -0.2794)
			(end 0.12065 -0.3048)
			(stroke
				(width 0.1)
				(type default)
			)
			(layer "F.Fab")
		)
		(fp_line
			(start -0.12065 -0.2794)
			(end 0.12065 -0.2794)
			(stroke
				(width 0.1)
				(type default)
			)
			(layer "F.Fab")
		)
		(fp_line
			(start 0.120396 0.2794)
			(end -0.12065 0.2794)
			(stroke
				(width 0.1)
				(type default)
			)
			(layer "F.Fab")
		)
		(fp_line
			(start -0.12065 0.2794)
			(end -0.12065 0.3048)
			(stroke
				(width 0.1)
				(type default)
			)
			(layer "F.Fab")
		)
		(fp_line
			(start 0.67945 0.3048)
			(end 0.120396 0.3048)
			(stroke
				(width 0.1)
				(type default)
			)
			(layer "F.Fab")
		)
		(fp_line
			(start 0.120396 0.3048)
			(end 0.120396 0.2794)
			(stroke
				(width 0.1)
				(type default)
			)
			(layer "F.Fab")
		)
		(fp_line
			(start -0.12065 0.3048)
			(end -0.67945 0.3048)
			(stroke
				(width 0.1)
				(type default)
			)
			(layer "F.Fab")
		)
		(fp_line
			(start -0.67945 0.3048)
			(end -0.67945 -0.305054)
			(stroke
				(width 0.1)
				(type default)
			)
			(layer "F.Fab")
		)
		(pad "1" smd circle
			(at -0.40005 0 90)
			(size 0 0)
			(layers "F.Cu" "F.Mask" "F.Paste")
			(net "P1V05_PCH_AUX_CS")
		)
		(pad "2" smd circle
			(at 0.40005 0 90)
			(size 0 0)
			(layers "F.Cu" "F.Mask" "F.Paste")
			(net "GND")
		)
	)
)
